# T6G (Grand Teton) — schematic netlist excerpt (pin names and nets, part order shuffled) for the footprints in the layout excerpt that follows; sources: Cadence DE-HDL packaged netlist, KiCad conversion of 04192023_DAF0TMB3IC0_F0TG_MB_C_brd_V02_OCP.brd

C3892  Q_CAP  22UF 4V 20% X6S  pkg C0402  page 68 : A = PVDD11_S3_P0 ; B = GND
R6775  Q_RES  4.7K 5% CHIP  pkg 0201LF  page 184 : A = RT_SMB_MUX_ADDR0 ; B = GND
PC275  Q_CAPP  220UF 4V 20% SPCAP  pkg SMLF  page 211 : A = PVDDCR_CPU0_P1 ; B = GND

(kicad_pcb
	(version 20260206)
	(generator "pcbnew")
	(generator_version "10.0")
	(general
		(thickness 1.6)
		(legacy_teardrops no)
	)
	(paper "A4")
	(title_block
		(title "04192023_DAF0TMB3IC0_F0TG_MB_C_brd_V02_OCP.brd")
		(comment 1 "Grand Teton / footprints 6089-6091 of 8354")
	)
	(layers
		(0 "F.Cu" signal "TOP")
		(4 "In1.Cu" signal "GND")
		(6 "In2.Cu" signal "IN1")
		(8 "In3.Cu" signal "GND1")
		(10 "In4.Cu" signal "IN2")
		(12 "In5.Cu" signal "GND2")
		(14 "In6.Cu" signal "IN3")
		(16 "In7.Cu" signal "GND3")
		(18 "In8.Cu" signal "VCC")
		(20 "In9.Cu" signal "VCC1")
		(22 "In10.Cu" signal "GND4")
		(24 "In11.Cu" signal "IN4")
		(26 "In12.Cu" signal "GND5")
		(28 "In13.Cu" signal "IN5")
		(30 "In14.Cu" signal "GND6")
		(32 "In15.Cu" signal "IN6")
		(34 "In16.Cu" signal "GND7")
		(2 "B.Cu" signal "BOTTOM")
		(9 "F.Adhes" user "F.Adhesive")
		(11 "B.Adhes" user "B.Adhesive")
		(13 "F.Paste" user "Package Geometry/Pastemask Top")
		(15 "B.Paste" user "Package Geometry/Pastemask Bottom")
		(5 "F.SilkS" user "Ref Des/Silkscreen Top")
		(7 "B.SilkS" user "Ref Des/Silkscreen Bottom")
		(1 "F.Mask" user "Board Geometry/Soldermask Top")
		(3 "B.Mask" user "Board Geometry/Soldermask Bottom")
		(17 "Dwgs.User" user "User.Drawings")
		(19 "Cmts.User" user "User.Comments")
		(21 "Eco1.User" user "User.Eco1")
		(23 "Eco2.User" user "User.Eco2")
		(25 "Edge.Cuts" user "Board Geometry/Outline")
		(27 "Margin" user)
		(31 "F.CrtYd" user "Package Geometry/Place Bound Top")
		(29 "B.CrtYd" user "Package Geometry/Place Bound Bottom")
		(35 "F.Fab" user "Ref Des/Assembly Top")
		(33 "B.Fab" user "Ref Des/Assembly Bottom")
	)
	(footprint ""
		(layer "B.Cu")
		(at 98.336354 -189.453012 90)
		(property "Reference" "PC275"
			(at 5.837936 0.970534 270)
			(unlocked yes)
			(layer "B.SilkS")
			(effects
				(font
					(size 0.7874 0.5842)
					(thickness 0.1524)
				)
				(justify left mirror)
			)
		)
		(property "Value" ""
			(at 0 0 90)
			(layer "B.Fab")
			(effects
				(font
					(size 1.27 1.27)
				)
				(justify mirror)
			)
		)
		(duplicate_pad_numbers_are_jumpers no)
		(fp_line
			(start 4.533392 -2.249932)
			(end -4.533392 -2.249932)
			(stroke
				(width 0.1524)
				(type default)
			)
			(layer "B.SilkS")
		)
		(fp_line
			(start -4.533392 -2.249932)
			(end -4.533392 2.249932)
			(stroke
				(width 0.1524)
				(type default)
			)
			(layer "B.SilkS")
		)
		(fp_line
			(start 4.533392 2.249932)
			(end 4.533392 -2.249932)
			(stroke
				(width 0.1524)
				(type default)
			)
			(layer "B.SilkS")
		)
		(fp_line
			(start -4.533392 2.249932)
			(end 4.533392 2.249932)
			(stroke
				(width 0.1524)
				(type default)
			)
			(layer "B.SilkS")
		)
		(fp_rect
			(start 4.533392 -2.326132)
			(end 5.39242 2.326132)
			(stroke
				(width 0)
				(type default)
			)
			(fill yes)
			(layer "B.SilkS")
		)
		(fp_line
			(start 3.750056 -2.249932)
			(end -3.750056 -2.249932)
			(stroke
				(width 0.1)
				(type default)
			)
			(layer "B.Fab")
		)
		(fp_line
			(start -3.750056 -2.249932)
			(end -3.750056 2.249932)
			(stroke
				(width 0.1)
				(type default)
			)
			(layer "B.Fab")
		)
		(fp_line
			(start 3.750056 2.249932)
			(end 3.750056 -2.249932)
			(stroke
				(width 0.1)
				(type default)
			)
			(layer "B.Fab")
		)
		(fp_line
			(start -3.750056 2.249932)
			(end 3.750056 2.249932)
			(stroke
				(width 0.1)
				(type default)
			)
			(layer "B.Fab")
		)
		(fp_text user "+"
			(at 6.322314 0.786384 0)
			(unlocked yes)
			(layer "B.SilkS")
			(effects
				(font
					(size 1.905 1.4224)
					(thickness 0.1524)
				)
				(justify left mirror)
			)
		)
		(fp_text user "-"
			(at -5.105908 0.958088 90)
			(unlocked yes)
			(layer "B.SilkS")
			(effects
				(font
					(size 1.905 1.4224)
					(thickness 0.1524)
				)
				(justify left mirror)
			)
		)
		(fp_text user "-"
			(at -4.8514 -0.14605 90)
			(unlocked yes)
			(layer "B.Fab")
			(effects
				(font
					(size 1.905 1.4224)
					(thickness 0.1524)
				)
				(justify left mirror)
			)
		)
		(fp_text user "+"
			(at 6.322314 0.786384 0)
			(unlocked yes)
			(layer "B.Fab")
			(effects
				(font
					(size 1.905 1.4224)
					(thickness 0.1524)
				)
				(justify left mirror)
			)
		)
		(pad "1" smd rect
			(at 3.199892 0 270)
			(size 2.413 2.8194)
			(layers "B.Cu" "B.Mask" "B.Paste")
			(net "PVDDCR_CPU0_P1")
		)
		(pad "2" smd rect
			(at -3.199892 0 270)
			(size 2.413 2.8194)
			(layers "B.Cu" "B.Mask" "B.Paste")
			(net "GND")
		)
	)
	(footprint ""
		(layer "B.Cu")
		(at 365.835692 -262.204962)
		(property "Reference" "C3892"
			(at 0 0 0)
			(layer "B.SilkS")
			(hide yes)
			(effects
				(font
					(size 1.27 1.27)
				)
				(justify mirror)
			)
		)
		(property "Value" ""
			(at 0 0 0)
			(layer "B.Fab")
			(effects
				(font
					(size 1.27 1.27)
				)
				(justify mirror)
			)
		)
		(duplicate_pad_numbers_are_jumpers no)
		(fp_line
			(start -0.7874 -0.4064)
			(end -0.7874 0.4064)
			(stroke
				(width 0.1524)
				(type default)
			)
			(layer "B.SilkS")
		)
		(fp_line
			(start -0.7874 0.4064)
			(end 0.7874 0.4064)
			(stroke
				(width 0.1524)
				(type default)
			)
			(layer "B.SilkS")
		)
		(fp_line
			(start 0.7874 -0.4064)
			(end -0.7874 -0.4064)
			(stroke
				(width 0.1524)
				(type default)
			)
			(layer "B.SilkS")
		)
		(fp_line
			(start 0.7874 0.4064)
			(end 0.7874 -0.4064)
			(stroke
				(width 0.1524)
				(type default)
			)
			(layer "B.SilkS")
		)
		(fp_line
			(start -0.67945 -0.3048)
			(end -0.67945 0.3048)
			(stroke
				(width 0.1)
				(type default)
			)
			(layer "B.Fab")
		)
		(fp_line
			(start -0.67945 0.3048)
			(end -0.120396 0.3048)
			(stroke
				(width 0.1)
				(type default)
			)
			(layer "B.Fab")
		)
		(fp_line
			(start -0.12065 -0.3048)
			(end -0.67945 -0.3048)
			(stroke
				(width 0.1)
				(type default)
			)
			(layer "B.Fab")
		)
		(fp_line
			(start -0.12065 -0.2794)
			(end -0.12065 -0.3048)
			(stroke
				(width 0.1)
				(type default)
			)
			(layer "B.Fab")
		)
		(fp_line
			(start -0.120396 0.2794)
			(end 0.12065 0.2794)
			(stroke
				(width 0.1)
				(type default)
			)
			(layer "B.Fab")
		)
		(fp_line
			(start -0.120396 0.3048)
			(end -0.120396 0.2794)
			(stroke
				(width 0.1)
				(type default)
			)
			(layer "B.Fab")
		)
		(fp_line
			(start 0.12065 -0.305054)
			(end 0.12065 -0.2794)
			(stroke
				(width 0.1)
				(type default)
			)
			(layer "B.Fab")
		)
		(fp_line
			(start 0.12065 -0.2794)
			(end -0.12065 -0.2794)
			(stroke
				(width 0.1)
				(type default)
			)
			(layer "B.Fab")
		)
		(fp_line
			(start 0.12065 0.2794)
			(end 0.12065 0.3048)
			(stroke
				(width 0.1)
				(type default)
			)
			(layer "B.Fab")
		)
		(fp_line
			(start 0.12065 0.3048)
			(end 0.67945 0.3048)
			(stroke
				(width 0.1)
				(type default)
			)
			(layer "B.Fab")
		)
		(fp_line
			(start 0.67945 -0.305054)
			(end 0.12065 -0.305054)
			(stroke
				(width 0.1)
				(type default)
			)
			(layer "B.Fab")
		)
		(fp_line
			(start 0.67945 0.3048)
			(end 0.67945 -0.305054)
			(stroke
				(width 0.1)
				(type default)
			)
			(layer "B.Fab")
		)
		(pad "1" smd circle
			(at 0.40005 0 180)
			(size 0 0)
			(layers "B.Cu" "B.Mask" "B.Paste")
			(net "PVDD11_S3_P0")
		)
		(pad "2" smd circle
			(at -0.40005 0 180)
			(size 0 0)
			(layers "B.Cu" "B.Mask" "B.Paste")
			(net "GND")
		)
	)
	(footprint ""
		(layer "B.Cu")
		(at 214.884 -330.708)
		(property "Reference" "R6775"
			(at 0 0 0)
			(layer "B.SilkS")
			(hide yes)
			(effects
				(font
					(size 1.27 1.27)
				)
				(justify mirror)
			)
		)
		(property "Value" ""
			(at 0 0 0)
			(layer "B.Fab")
			(effects
				(font
					(size 1.27 1.27)
				)
				(justify mirror)
			)
		)
		(duplicate_pad_numbers_are_jumpers no)
		(fp_line
			(start -0.32512 -0.175006)
			(end -0.32512 0.175006)
			(stroke
				(width 0.1)
				(type default)
			)
			(layer "B.Fab")
		)
		(fp_line
			(start -0.32512 0.175006)
			(end 0.32512 0.175006)
			(stroke
				(width 0.1)
				(type default)
			)
			(layer "B.Fab")
		)
		(fp_line
			(start 0.32512 -0.175006)
			(end -0.32512 -0.175006)
			(stroke
				(width 0.1)
				(type default)
			)
			(layer "B.Fab")
		)
		(fp_line
			(start 0.32512 0.175006)
			(end 0.32512 -0.175006)
			(stroke
				(width 0.1)
				(type default)
			)
			(layer "B.Fab")
		)
		(pad "1" smd rect
			(at 0.2667 0 180)
			(size 0.3048 0.381)
			(layers "B.Cu" "B.Mask" "B.Paste")
			(net "RT_SMB_MUX_ADDR0")
		)
		(pad "2" smd rect
			(at -0.2667 0)
			(size 0.3048 0.381)
			(layers "B.Cu" "B.Mask" "B.Paste")
			(net "GND")
		)
	)
)
